(kicad_pcb
	(version 20260206)
	(generator "pcbnew")
	(generator_version "10.0")
	(general
		(thickness 1.6)
		(legacy_teardrops no)
	)
	(paper "A4")
	(title_block
		(title "01162023_DA0F0TEBIF0_F0T_Expander_BD_F_brd_V02_OCP.brd")
		(comment 1 "Grand Teton / footprints 9517-9523 of 9728")
	)
	(layers
		(0 "F.Cu" signal "TOP")
		(4 "In1.Cu" signal "GND")
		(6 "In2.Cu" signal "VCC")
		(8 "In3.Cu" signal "VCC1")
		(10 "In4.Cu" signal "GND1")
		(12 "In5.Cu" signal "IN1")
		(14 "In6.Cu" signal "GND2")
		(16 "In7.Cu" signal "IN2")
		(18 "In8.Cu" signal "GND3")
		(20 "In9.Cu" signal "IN3")
		(22 "In10.Cu" signal "GND4")
		(24 "In11.Cu" signal "IN4")
		(26 "In12.Cu" signal "GND5")
		(28 "In13.Cu" signal "IN5")
		(30 "In14.Cu" signal "GND6")
		(32 "In15.Cu" signal "IN6")
		(34 "In16.Cu" signal "GND7")
		(2 "B.Cu" signal "BOTTOM")
		(9 "F.Adhes" user "F.Adhesive")
		(11 "B.Adhes" user "B.Adhesive")
		(13 "F.Paste" user "Package Geometry/Pastemask Top")
		(15 "B.Paste" user "Package Geometry/Pastemask Bottom")
		(5 "F.SilkS" user "Ref Des/Silkscreen Top")
		(7 "B.SilkS" user "Ref Des/Silkscreen Bottom")
		(1 "F.Mask" user "Board Geometry/Soldermask Top")
		(3 "B.Mask" user "Board Geometry/Soldermask Bottom")
		(17 "Dwgs.User" user "User.Drawings")
		(19 "Cmts.User" user "User.Comments")
		(21 "Eco1.User" user "User.Eco1")
		(23 "Eco2.User" user "User.Eco2")
		(25 "Edge.Cuts" user "Board Geometry/Outline")
		(27 "Margin" user)
		(31 "F.CrtYd" user "Package Geometry/Place Bound Top")
		(29 "B.CrtYd" user "Package Geometry/Place Bound Bottom")
		(35 "F.Fab" user "Ref Des/Assembly Top")
		(33 "B.Fab" user "Ref Des/Assembly Bottom")
	)
	(footprint ""
		(layer "B.Cu")
		(at 143.790162 -243.282978 90)
		(property "Reference" "R6571"
			(at 0 0 90)
			(layer "B.SilkS")
			(hide yes)
			(effects
				(font
					(size 1.27 1.27)
				)
				(justify mirror)
			)
		)
		(property "Value" ""
			(at 0 0 90)
			(layer "B.Fab")
			(effects
				(font
					(size 1.27 1.27)
				)
				(justify mirror)
			)
		)
		(duplicate_pad_numbers_are_jumpers no)
		(fp_line
			(start 0.7874 -0.4064)
			(end -0.7874 -0.4064)
			(stroke
				(width 0.1524)
				(type default)
			)
			(layer "B.SilkS")
		)
		(fp_line
			(start -0.7874 -0.4064)
			(end -0.7874 0.4064)
			(stroke
				(width 0.1524)
				(type default)
			)
			(layer "B.SilkS")
		)
		(fp_line
			(start 0.7874 0.4064)
			(end 0.7874 -0.4064)
			(stroke
				(width 0.1524)
				(type default)
			)
			(layer "B.SilkS")
		)
		(fp_line
			(start -0.7874 0.4064)
			(end 0.7874 0.4064)
			(stroke
				(width 0.1524)
				(type default)
			)
			(layer "B.SilkS")
		)
		(fp_line
			(start 0.67945 -0.305054)
			(end 0.12065 -0.305054)
			(stroke
				(width 0.1)
				(type default)
			)
			(layer "B.Fab")
		)
		(fp_line
			(start 0.12065 -0.305054)
			(end 0.12065 -0.2794)
			(stroke
				(width 0.1)
				(type default)
			)
			(layer "B.Fab")
		)
		(fp_line
			(start -0.12065 -0.3048)
			(end -0.67945 -0.3048)
			(stroke
				(width 0.1)
				(type default)
			)
			(layer "B.Fab")
		)
		(fp_line
			(start -0.67945 -0.3048)
			(end -0.67945 0.3048)
			(stroke
				(width 0.1)
				(type default)
			)
			(layer "B.Fab")
		)
		(fp_line
			(start 0.12065 -0.2794)
			(end -0.12065 -0.2794)
			(stroke
				(width 0.1)
				(type default)
			)
			(layer "B.Fab")
		)
		(fp_line
			(start -0.12065 -0.2794)
			(end -0.12065 -0.3048)
			(stroke
				(width 0.1)
				(type default)
			)
			(layer "B.Fab")
		)
		(fp_line
			(start 0.12065 0.2794)
			(end 0.12065 0.3048)
			(stroke
				(width 0.1)
				(type default)
			)
			(layer "B.Fab")
		)
		(fp_line
			(start -0.120396 0.2794)
			(end 0.12065 0.2794)
			(stroke
				(width 0.1)
				(type default)
			)
			(layer "B.Fab")
		)
		(fp_line
			(start 0.67945 0.3048)
			(end 0.67945 -0.305054)
			(stroke
				(width 0.1)
				(type default)
			)
			(layer "B.Fab")
		)
		(fp_line
			(start 0.12065 0.3048)
			(end 0.67945 0.3048)
			(stroke
				(width 0.1)
				(type default)
			)
			(layer "B.Fab")
		)
		(fp_line
			(start -0.120396 0.3048)
			(end -0.120396 0.2794)
			(stroke
				(width 0.1)
				(type default)
			)
			(layer "B.Fab")
		)
		(fp_line
			(start -0.67945 0.3048)
			(end -0.120396 0.3048)
			(stroke
				(width 0.1)
				(type default)
			)
			(layer "B.Fab")
		)
		(pad "1" smd circle
			(at 0.40005 0 270)
			(size 0 0)
			(layers "B.Cu" "B.Mask" "B.Paste")
			(net "P3V3_AUX")
		)
		(pad "2" smd circle
			(at -0.40005 0 270)
			(size 0 0)
			(layers "B.Cu" "B.Mask" "B.Paste")
			(net "PEX1_P1V8_PLL_EN")
		)
	)
	(footprint ""
		(layer "B.Cu")
		(at 237.609634 -348.475554 180)
		(property "Reference" "PR7144"
			(at 0 0 0)
			(layer "B.SilkS")
			(hide yes)
			(effects
				(font
					(size 1.27 1.27)
				)
				(justify mirror)
			)
		)
		(property "Value" ""
			(at 0 0 0)
			(layer "B.Fab")
			(effects
				(font
					(size 1.27 1.27)
				)
				(justify mirror)
			)
		)
		(duplicate_pad_numbers_are_jumpers no)
		(fp_line
			(start 0.7874 0.4064)
			(end 0.7874 -0.4064)
			(stroke
				(width 0.1524)
				(type default)
			)
			(layer "B.SilkS")
		)
		(fp_line
			(start 0.7874 -0.4064)
			(end -0.7874 -0.4064)
			(stroke
				(width 0.1524)
				(type default)
			)
			(layer "B.SilkS")
		)
		(fp_line
			(start -0.7874 0.4064)
			(end 0.7874 0.4064)
			(stroke
				(width 0.1524)
				(type default)
			)
			(layer "B.SilkS")
		)
		(fp_line
			(start -0.7874 -0.4064)
			(end -0.7874 0.4064)
			(stroke
				(width 0.1524)
				(type default)
			)
			(layer "B.SilkS")
		)
		(fp_line
			(start 0.67945 0.3048)
			(end 0.67945 -0.305054)
			(stroke
				(width 0.1)
				(type default)
			)
			(layer "B.Fab")
		)
		(fp_line
			(start 0.67945 -0.305054)
			(end 0.12065 -0.305054)
			(stroke
				(width 0.1)
				(type default)
			)
			(layer "B.Fab")
		)
		(fp_line
			(start 0.12065 0.3048)
			(end 0.67945 0.3048)
			(stroke
				(width 0.1)
				(type default)
			)
			(layer "B.Fab")
		)
		(fp_line
			(start 0.12065 0.2794)
			(end 0.12065 0.3048)
			(stroke
				(width 0.1)
				(type default)
			)
			(layer "B.Fab")
		)
		(fp_line
			(start 0.12065 -0.2794)
			(end -0.12065 -0.2794)
			(stroke
				(width 0.1)
				(type default)
			)
			(layer "B.Fab")
		)
		(fp_line
			(start 0.12065 -0.305054)
			(end 0.12065 -0.2794)
			(stroke
				(width 0.1)
				(type default)
			)
			(layer "B.Fab")
		)
		(fp_line
			(start -0.120396 0.3048)
			(end -0.120396 0.2794)
			(stroke
				(width 0.1)
				(type default)
			)
			(layer "B.Fab")
		)
		(fp_line
			(start -0.120396 0.2794)
			(end 0.12065 0.2794)
			(stroke
				(width 0.1)
				(type default)
			)
			(layer "B.Fab")
		)
		(fp_line
			(start -0.12065 -0.2794)
			(end -0.12065 -0.3048)
			(stroke
				(width 0.1)
				(type default)
			)
			(layer "B.Fab")
		)
		(fp_line
			(start -0.12065 -0.3048)
			(end -0.67945 -0.3048)
			(stroke
				(width 0.1)
				(type default)
			)
			(layer "B.Fab")
		)
		(fp_line
			(start -0.67945 0.3048)
			(end -0.120396 0.3048)
			(stroke
				(width 0.1)
				(type default)
			)
			(layer "B.Fab")
		)
		(fp_line
			(start -0.67945 -0.3048)
			(end -0.67945 0.3048)
			(stroke
				(width 0.1)
				(type default)
			)
			(layer "B.Fab")
		)
		(pad "1" smd circle
			(at 0.40005 0)
			(size 0 0)
			(layers "B.Cu" "B.Mask" "B.Paste")
			(net "P12V_HSC_ADC_P")
		)
		(pad "2" smd circle
			(at -0.40005 0)
			(size 0 0)
			(layers "B.Cu" "B.Mask" "B.Paste")
			(net "P12V_HSC_SENSE1_P")
		)
	)
	(footprint ""
		(layer "B.Cu")
		(at 404.625048 -293.99992 90)
		(property "Reference" "C1883"
			(at 0 0 90)
			(layer "B.SilkS")
			(hide yes)
			(effects
				(font
					(size 1.27 1.27)
				)
				(justify mirror)
			)
		)
		(property "Value" ""
			(at 0 0 90)
			(layer "B.Fab")
			(effects
				(font
					(size 1.27 1.27)
				)
				(justify mirror)
			)
		)
		(duplicate_pad_numbers_are_jumpers no)
		(fp_line
			(start 0.299974 -0.150114)
			(end -0.299974 -0.150114)
			(stroke
				(width 0.1)
				(type default)
			)
			(layer "B.Fab")
		)
		(fp_line
			(start -0.299974 -0.150114)
			(end -0.299974 0.150114)
			(stroke
				(width 0.1)
				(type default)
			)
			(layer "B.Fab")
		)
		(fp_line
			(start 0.299974 0.150114)
			(end 0.299974 -0.150114)
			(stroke
				(width 0.1)
				(type default)
			)
			(layer "B.Fab")
		)
		(fp_line
			(start -0.299974 0.150114)
			(end 0.299974 0.150114)
			(stroke
				(width 0.1)
				(type default)
			)
			(layer "B.Fab")
		)
		(pad "1" smd rect
			(at 0.2667 0 270)
			(size 0.3048 0.381)
			(layers "B.Cu" "B.Mask" "B.Paste")
			(net "P0V8_PEX3")
		)
		(pad "2" smd rect
			(at -0.2667 0 270)
			(size 0.3048 0.381)
			(layers "B.Cu" "B.Mask" "B.Paste")
			(net "GND")
		)
	)
	(footprint ""
		(layer "B.Cu")
		(at 132.8928 -282.173172 90)
		(property "Reference" "R6765"
			(at 0 0 90)
			(layer "B.SilkS")
			(hide yes)
			(effects
				(font
					(size 1.27 1.27)
				)
				(justify mirror)
			)
		)
		(property "Value" ""
			(at 0 0 90)
			(layer "B.Fab")
			(effects
				(font
					(size 1.27 1.27)
				)
				(justify mirror)
			)
		)
		(duplicate_pad_numbers_are_jumpers no)
		(fp_line
			(start 0.7874 -0.4064)
			(end -0.7874 -0.4064)
			(stroke
				(width 0.1524)
				(type default)
			)
			(layer "B.SilkS")
		)
		(fp_line
			(start -0.7874 -0.4064)
			(end -0.7874 0.4064)
			(stroke
				(width 0.1524)
				(type default)
			)
			(layer "B.SilkS")
		)
		(fp_line
			(start 0.7874 0.4064)
			(end 0.7874 -0.4064)
			(stroke
				(width 0.1524)
				(type default)
			)
			(layer "B.SilkS")
		)
		(fp_line
			(start -0.7874 0.4064)
			(end 0.7874 0.4064)
			(stroke
				(width 0.1524)
				(type default)
			)
			(layer "B.SilkS")
		)
		(fp_line
			(start 0.67945 -0.305054)
			(end 0.12065 -0.305054)
			(stroke
				(width 0.1)
				(type default)
			)
			(layer "B.Fab")
		)
		(fp_line
			(start 0.12065 -0.305054)
			(end 0.12065 -0.2794)
			(stroke
				(width 0.1)
				(type default)
			)
			(layer "B.Fab")
		)
		(fp_line
			(start -0.12065 -0.3048)
			(end -0.67945 -0.3048)
			(stroke
				(width 0.1)
				(type default)
			)
			(layer "B.Fab")
		)
		(fp_line
			(start -0.67945 -0.3048)
			(end -0.67945 0.3048)
			(stroke
				(width 0.1)
				(type default)
			)
			(layer "B.Fab")
		)
		(fp_line
			(start 0.12065 -0.2794)
			(end -0.12065 -0.2794)
			(stroke
				(width 0.1)
				(type default)
			)
			(layer "B.Fab")
		)
		(fp_line
			(start -0.12065 -0.2794)
			(end -0.12065 -0.3048)
			(stroke
				(width 0.1)
				(type default)
			)
			(layer "B.Fab")
		)
		(fp_line
			(start 0.12065 0.2794)
			(end 0.12065 0.3048)
			(stroke
				(width 0.1)
				(type default)
			)
			(layer "B.Fab")
		)
		(fp_line
			(start -0.120396 0.2794)
			(end 0.12065 0.2794)
			(stroke
				(width 0.1)
				(type default)
			)
			(layer "B.Fab")
		)
		(fp_line
			(start 0.67945 0.3048)
			(end 0.67945 -0.305054)
			(stroke
				(width 0.1)
				(type default)
			)
			(layer "B.Fab")
		)
		(fp_line
			(start 0.12065 0.3048)
			(end 0.67945 0.3048)
			(stroke
				(width 0.1)
				(type default)
			)
			(layer "B.Fab")
		)
		(fp_line
			(start -0.120396 0.3048)
			(end -0.120396 0.2794)
			(stroke
				(width 0.1)
				(type default)
			)
			(layer "B.Fab")
		)
		(fp_line
			(start -0.67945 0.3048)
			(end -0.120396 0.3048)
			(stroke
				(width 0.1)
				(type default)
			)
			(layer "B.Fab")
		)
		(pad "1" smd circle
			(at 0.40005 0 270)
			(size 0 0)
			(layers "B.Cu" "B.Mask" "B.Paste")
			(net "P0V8_PEX1_VCC2")
		)
		(pad "2" smd circle
			(at -0.40005 0 270)
			(size 0 0)
			(layers "B.Cu" "B.Mask" "B.Paste")
			(net "P0V8_PEX0_EN4")
		)
	)
	(footprint ""
		(layer "B.Cu")
		(at 356.524306 -244.139974)
		(property "Reference" "R5893"
			(at 0 0 0)
			(layer "B.SilkS")
			(hide yes)
			(effects
				(font
					(size 1.27 1.27)
				)
				(justify mirror)
			)
		)
		(property "Value" ""
			(at 0 0 0)
			(layer "B.Fab")
			(effects
				(font
					(size 1.27 1.27)
				)
				(justify mirror)
			)
		)
		(duplicate_pad_numbers_are_jumpers no)
		(fp_line
			(start -0.7874 -0.4064)
			(end -0.7874 0.4064)
			(stroke
				(width 0.1524)
				(type default)
			)
			(layer "B.SilkS")
		)
		(fp_line
			(start -0.7874 0.4064)
			(end 0.7874 0.4064)
			(stroke
				(width 0.1524)
				(type default)
			)
			(layer "B.SilkS")
		)
		(fp_line
			(start 0.7874 -0.4064)
			(end -0.7874 -0.4064)
			(stroke
				(width 0.1524)
				(type default)
			)
			(layer "B.SilkS")
		)
		(fp_line
			(start 0.7874 0.4064)
			(end 0.7874 -0.4064)
			(stroke
				(width 0.1524)
				(type default)
			)
			(layer "B.SilkS")
		)
		(fp_line
			(start -0.67945 -0.3048)
			(end -0.67945 0.3048)
			(stroke
				(width 0.1)
				(type default)
			)
			(layer "B.Fab")
		)
		(fp_line
			(start -0.67945 0.3048)
			(end -0.120396 0.3048)
			(stroke
				(width 0.1)
				(type default)
			)
			(layer "B.Fab")
		)
		(fp_line
			(start -0.12065 -0.3048)
			(end -0.67945 -0.3048)
			(stroke
				(width 0.1)
				(type default)
			)
			(layer "B.Fab")
		)
		(fp_line
			(start -0.12065 -0.2794)
			(end -0.12065 -0.3048)
			(stroke
				(width 0.1)
				(type default)
			)
			(layer "B.Fab")
		)
		(fp_line
			(start -0.120396 0.2794)
			(end 0.12065 0.2794)
			(stroke
				(width 0.1)
				(type default)
			)
			(layer "B.Fab")
		)
		(fp_line
			(start -0.120396 0.3048)
			(end -0.120396 0.2794)
			(stroke
				(width 0.1)
				(type default)
			)
			(layer "B.Fab")
		)
		(fp_line
			(start 0.12065 -0.305054)
			(end 0.12065 -0.2794)
			(stroke
				(width 0.1)
				(type default)
			)
			(layer "B.Fab")
		)
		(fp_line
			(start 0.12065 -0.2794)
			(end -0.12065 -0.2794)
			(stroke
				(width 0.1)
				(type default)
			)
			(layer "B.Fab")
		)
		(fp_line
			(start 0.12065 0.2794)
			(end 0.12065 0.3048)
			(stroke
				(width 0.1)
				(type default)
			)
			(layer "B.Fab")
		)
		(fp_line
			(start 0.12065 0.3048)
			(end 0.67945 0.3048)
			(stroke
				(width 0.1)
				(type default)
			)
			(layer "B.Fab")
		)
		(fp_line
			(start 0.67945 -0.305054)
			(end 0.12065 -0.305054)
			(stroke
				(width 0.1)
				(type default)
			)
			(layer "B.Fab")
		)
		(fp_line
			(start 0.67945 0.3048)
			(end 0.67945 -0.305054)
			(stroke
				(width 0.1)
				(type default)
			)
			(layer "B.Fab")
		)
		(pad "1" smd circle
			(at 0.40005 0 180)
			(size 0 0)
			(layers "B.Cu" "B.Mask" "B.Paste")
			(net "P3V3_AUX")
		)
		(pad "2" smd circle
			(at -0.40005 0 180)
			(size 0 0)
			(layers "B.Cu" "B.Mask" "B.Paste")
			(net "JP_FPGA_DEBUG_N")
		)
	)
	(footprint ""
		(layer "B.Cu")
		(at 357.9876 -361.6198 180)
		(property "Reference" "R6315"
			(at 0 0 0)
			(layer "B.SilkS")
			(hide yes)
			(effects
				(font
					(size 1.27 1.27)
				)
				(justify mirror)
			)
		)
		(property "Value" ""
			(at 0 0 0)
			(layer "B.Fab")
			(effects
				(font
					(size 1.27 1.27)
				)
				(justify mirror)
			)
		)
		(duplicate_pad_numbers_are_jumpers no)
		(fp_line
			(start 0.7874 0.4064)
			(end 0.7874 -0.4064)
			(stroke
				(width 0.1524)
				(type default)
			)
			(layer "B.SilkS")
		)
		(fp_line
			(start 0.7874 -0.4064)
			(end -0.7874 -0.4064)
			(stroke
				(width 0.1524)
				(type default)
			)
			(layer "B.SilkS")
		)
		(fp_line
			(start -0.7874 0.4064)
			(end 0.7874 0.4064)
			(stroke
				(width 0.1524)
				(type default)
			)
			(layer "B.SilkS")
		)
		(fp_line
			(start -0.7874 -0.4064)
			(end -0.7874 0.4064)
			(stroke
				(width 0.1524)
				(type default)
			)
			(layer "B.SilkS")
		)
		(fp_line
			(start 0.67945 0.3048)
			(end 0.67945 -0.305054)
			(stroke
				(width 0.1)
				(type default)
			)
			(layer "B.Fab")
		)
		(fp_line
			(start 0.67945 -0.305054)
			(end 0.12065 -0.305054)
			(stroke
				(width 0.1)
				(type default)
			)
			(layer "B.Fab")
		)
		(fp_line
			(start 0.12065 0.3048)
			(end 0.67945 0.3048)
			(stroke
				(width 0.1)
				(type default)
			)
			(layer "B.Fab")
		)
		(fp_line
			(start 0.12065 0.2794)
			(end 0.12065 0.3048)
			(stroke
				(width 0.1)
				(type default)
			)
			(layer "B.Fab")
		)
		(fp_line
			(start 0.12065 -0.2794)
			(end -0.12065 -0.2794)
			(stroke
				(width 0.1)
				(type default)
			)
			(layer "B.Fab")
		)
		(fp_line
			(start 0.12065 -0.305054)
			(end 0.12065 -0.2794)
			(stroke
				(width 0.1)
				(type default)
			)
			(layer "B.Fab")
		)
		(fp_line
			(start -0.120396 0.3048)
			(end -0.120396 0.2794)
			(stroke
				(width 0.1)
				(type default)
			)
			(layer "B.Fab")
		)
		(fp_line
			(start -0.120396 0.2794)
			(end 0.12065 0.2794)
			(stroke
				(width 0.1)
				(type default)
			)
			(layer "B.Fab")
		)
		(fp_line
			(start -0.12065 -0.2794)
			(end -0.12065 -0.3048)
			(stroke
				(width 0.1)
				(type default)
			)
			(layer "B.Fab")
		)
		(fp_line
			(start -0.12065 -0.3048)
			(end -0.67945 -0.3048)
			(stroke
				(width 0.1)
				(type default)
			)
			(layer "B.Fab")
		)
		(fp_line
			(start -0.67945 0.3048)
			(end -0.120396 0.3048)
			(stroke
				(width 0.1)
				(type default)
			)
			(layer "B.Fab")
		)
		(fp_line
			(start -0.67945 -0.3048)
			(end -0.67945 0.3048)
			(stroke
				(width 0.1)
				(type default)
			)
			(layer "B.Fab")
		)
		(pad "1" smd circle
			(at 0.40005 0)
			(size 0 0)
			(layers "B.Cu" "B.Mask" "B.Paste")
			(net "PWRGD_P12V_AUX_R")
		)
		(pad "2" smd circle
			(at -0.40005 0)
			(size 0 0)
			(layers "B.Cu" "B.Mask" "B.Paste")
			(net "SWB_HSC_PWRGD")
		)
	)
	(footprint ""
		(layer "B.Cu")
		(at 341.460328 -308.613556 90)
		(property "Reference" "C4317"
			(at 0 0 90)
			(layer "B.SilkS")
			(hide yes)
			(effects
				(font
					(size 1.27 1.27)
				)
				(justify mirror)
			)
		)
		(property "Value" ""
			(at 0 0 90)
			(layer "B.Fab")
			(effects
				(font
					(size 1.27 1.27)
				)
				(justify mirror)
			)
		)
		(duplicate_pad_numbers_are_jumpers no)
		(fp_line
			(start 1.2954 -0.5842)
			(end -1.2954 -0.5842)
			(stroke
				(width 0.1524)
				(type default)
			)
			(layer "B.SilkS")
		)
		(fp_line
			(start -1.2954 -0.5842)
			(end -1.2954 0.5842)
			(stroke
				(width 0.1524)
				(type default)
			)
			(layer "B.SilkS")
		)
		(fp_line
			(start 1.2954 0.5842)
			(end 1.2954 -0.5842)
			(stroke
				(width 0.1524)
				(type default)
			)
			(layer "B.SilkS")
		)
		(fp_line
			(start -1.2954 0.5842)
			(end 1.2954 0.5842)
			(stroke
				(width 0.1524)
				(type default)
			)
			(layer "B.SilkS")
		)
		(fp_line
			(start 0.8636 -0.4572)
			(end -0.8636 -0.4572)
			(stroke
				(width 0.1)
				(type default)
			)
			(layer "B.Fab")
		)
		(fp_line
			(start -0.8636 -0.4572)
			(end -0.8636 -0.4064)
			(stroke
				(width 0.1)
				(type default)
			)
			(layer "B.Fab")
		)
		(fp_line
			(start 1.1938 -0.4064)
			(end 0.8636 -0.4064)
			(stroke
				(width 0.1)
				(type default)
			)
			(layer "B.Fab")
		)
		(fp_line
			(start 0.8636 -0.4064)
			(end 0.8636 -0.4572)
			(stroke
				(width 0.1)
				(type default)
			)
			(layer "B.Fab")
		)
		(fp_line
			(start -0.8636 -0.4064)
			(end -1.1938 -0.4064)
			(stroke
				(width 0.1)
				(type default)
			)
			(layer "B.Fab")
		)
		(fp_line
			(start -1.1938 -0.4064)
			(end -1.1938 0.4064)
			(stroke
				(width 0.1)
				(type default)
			)
			(layer "B.Fab")
		)
		(fp_line
			(start 1.1938 0.4064)
			(end 1.1938 -0.4064)
			(stroke
				(width 0.1)
				(type default)
			)
			(layer "B.Fab")
		)
		(fp_line
			(start 0.8636 0.4064)
			(end 1.1938 0.4064)
			(stroke
				(width 0.1)
				(type default)
			)
			(layer "B.Fab")
		)
		(fp_line
			(start -0.8636 0.4064)
			(end -0.8636 0.4572)
			(stroke
				(width 0.1)
				(type default)
			)
			(layer "B.Fab")
		)
		(fp_line
			(start -1.1938 0.4064)
			(end -0.8636 0.4064)
			(stroke
				(width 0.1)
				(type default)
			)
			(layer "B.Fab")
		)
		(fp_line
			(start 0.8636 0.4572)
			(end 0.8636 0.4064)
			(stroke
				(width 0.1)
				(type default)
			)
			(layer "B.Fab")
		)
		(fp_line
			(start -0.8636 0.4572)
			(end 0.8636 0.4572)
			(stroke
				(width 0.1)
				(type default)
			)
			(layer "B.Fab")
		)
		(pad "1" smd rect
			(at 0.7366 0)
			(size 0.7112 0.8128)
			(layers "B.Cu" "B.Mask" "B.Paste")
			(net "P0V8_PEX2")
		)
		(pad "2" smd rect
			(at -0.7366 0)
			(size 0.7112 0.8128)
			(layers "B.Cu" "B.Mask" "B.Paste")
			(net "GND")
		)
	)
)
